# S9S_MB_2U (Grand Teton) — schematic netlist excerpt (pin names and nets, part order shuffled) for the footprints in the layout excerpt that follows; sources: Cadence DE-HDL packaged netlist, KiCad conversion of 03242023_DA0F0TMBIJ0_F0T_Motherboard_J_brd_V01_OCP.brd

R4726  Q_RES  4.7K 5% CHIP  pkg 0402LF  page 144 : A = P3V3_AUX ; B = PRSNT_SWB_ISO_N
R4616  Q_RES  33.2 1% CHIP  pkg 0402LF  page 164 : A = HP_OCP_V3_2_RST ; B = HP_OCP_V3_2_RST_R

(kicad_pcb
	(version 20260206)
	(generator "pcbnew")
	(generator_version "10.0")
	(general
		(thickness 1.6)
		(legacy_teardrops no)
	)
	(paper "A4")
	(title_block
		(title "03242023_DA0F0TMBIJ0_F0T_Motherboard_J_brd_V01_OCP.brd")
		(comment 1 "Grand Teton / footprints 3020-3021 of 6105")
	)
	(layers
		(0 "F.Cu" signal "TOP")
		(4 "In1.Cu" signal "GND")
		(6 "In2.Cu" signal "IN1")
		(8 "In3.Cu" signal "GND1")
		(10 "In4.Cu" signal "IN2")
		(12 "In5.Cu" signal "GND2")
		(14 "In6.Cu" signal "IN3")
		(16 "In7.Cu" signal "GND3")
		(18 "In8.Cu" signal "VCC")
		(20 "In9.Cu" signal "VCC1")
		(22 "In10.Cu" signal "GND4")
		(24 "In11.Cu" signal "IN4")
		(26 "In12.Cu" signal "GND5")
		(28 "In13.Cu" signal "IN5")
		(30 "In14.Cu" signal "GND6")
		(32 "In15.Cu" signal "IN6")
		(34 "In16.Cu" signal "GND7")
		(2 "B.Cu" signal "BOTTOM")
		(9 "F.Adhes" user "F.Adhesive")
		(11 "B.Adhes" user "B.Adhesive")
		(13 "F.Paste" user "Package Geometry/Pastemask Top")
		(15 "B.Paste" user "Package Geometry/Pastemask Bottom")
		(5 "F.SilkS" user "Ref Des/Silkscreen Top")
		(7 "B.SilkS" user "Ref Des/Silkscreen Bottom")
		(1 "F.Mask" user "Board Geometry/Soldermask Top")
		(3 "B.Mask" user "Board Geometry/Soldermask Bottom")
		(17 "Dwgs.User" user "User.Drawings")
		(19 "Cmts.User" user "User.Comments")
		(21 "Eco1.User" user "User.Eco1")
		(23 "Eco2.User" user "User.Eco2")
		(25 "Edge.Cuts" user "Board Geometry/Outline")
		(27 "Margin" user)
		(31 "F.CrtYd" user "Package Geometry/Place Bound Top")
		(29 "B.CrtYd" user "Package Geometry/Place Bound Bottom")
		(35 "F.Fab" user "Ref Des/Assembly Top")
		(33 "B.Fab" user "Ref Des/Assembly Bottom")
	)
	(footprint ""
		(layer "F.Cu")
		(at 84.5058 -35.651948 90)
		(property "Reference" "R4616"
			(at 0 0 90)
			(layer "F.SilkS")
			(hide yes)
			(effects
				(font
					(size 1.27 1.27)
				)
			)
		)
		(property "Value" ""
			(at 0 0 90)
			(layer "F.Fab")
			(effects
				(font
					(size 1.27 1.27)
				)
			)
		)
		(duplicate_pad_numbers_are_jumpers no)
		(fp_line
			(start 0.7874 -0.4064)
			(end 0.7874 0.4064)
			(stroke
				(width 0.1524)
				(type default)
			)
			(layer "F.SilkS")
		)
		(fp_line
			(start -0.7874 -0.4064)
			(end 0.7874 -0.4064)
			(stroke
				(width 0.1524)
				(type default)
			)
			(layer "F.SilkS")
		)
		(fp_line
			(start 0.7874 0.4064)
			(end -0.7874 0.4064)
			(stroke
				(width 0.1524)
				(type default)
			)
			(layer "F.SilkS")
		)
		(fp_line
			(start -0.7874 0.4064)
			(end -0.7874 -0.4064)
			(stroke
				(width 0.1524)
				(type default)
			)
			(layer "F.SilkS")
		)
		(fp_line
			(start -0.12065 -0.305054)
			(end -0.12065 -0.2794)
			(stroke
				(width 0.1)
				(type default)
			)
			(layer "F.Fab")
		)
		(fp_line
			(start -0.67945 -0.305054)
			(end -0.12065 -0.305054)
			(stroke
				(width 0.1)
				(type default)
			)
			(layer "F.Fab")
		)
		(fp_line
			(start 0.67945 -0.3048)
			(end 0.67945 0.3048)
			(stroke
				(width 0.1)
				(type default)
			)
			(layer "F.Fab")
		)
		(fp_line
			(start 0.12065 -0.3048)
			(end 0.67945 -0.3048)
			(stroke
				(width 0.1)
				(type default)
			)
			(layer "F.Fab")
		)
		(fp_line
			(start 0.12065 -0.2794)
			(end 0.12065 -0.3048)
			(stroke
				(width 0.1)
				(type default)
			)
			(layer "F.Fab")
		)
		(fp_line
			(start -0.12065 -0.2794)
			(end 0.12065 -0.2794)
			(stroke
				(width 0.1)
				(type default)
			)
			(layer "F.Fab")
		)
		(fp_line
			(start 0.120396 0.2794)
			(end -0.12065 0.2794)
			(stroke
				(width 0.1)
				(type default)
			)
			(layer "F.Fab")
		)
		(fp_line
			(start -0.12065 0.2794)
			(end -0.12065 0.3048)
			(stroke
				(width 0.1)
				(type default)
			)
			(layer "F.Fab")
		)
		(fp_line
			(start 0.67945 0.3048)
			(end 0.120396 0.3048)
			(stroke
				(width 0.1)
				(type default)
			)
			(layer "F.Fab")
		)
		(fp_line
			(start 0.120396 0.3048)
			(end 0.120396 0.2794)
			(stroke
				(width 0.1)
				(type default)
			)
			(layer "F.Fab")
		)
		(fp_line
			(start -0.12065 0.3048)
			(end -0.67945 0.3048)
			(stroke
				(width 0.1)
				(type default)
			)
			(layer "F.Fab")
		)
		(fp_line
			(start -0.67945 0.3048)
			(end -0.67945 -0.305054)
			(stroke
				(width 0.1)
				(type default)
			)
			(layer "F.Fab")
		)
		(pad "1" smd circle
			(at -0.40005 0 90)
			(size 0 0)
			(layers "F.Cu" "F.Mask" "F.Paste")
			(net "HP_OCP_V3_2_RST")
		)
		(pad "2" smd circle
			(at 0.40005 0 90)
			(size 0 0)
			(layers "F.Cu" "F.Mask" "F.Paste")
			(net "HP_OCP_V3_2_RST_R")
		)
	)
	(footprint ""
		(layer "F.Cu")
		(at 104.8258 -408.2796)
		(property "Reference" "R4726"
			(at 0 0 0)
			(layer "F.SilkS")
			(hide yes)
			(effects
				(font
					(size 1.27 1.27)
				)
			)
		)
		(property "Value" ""
			(at 0 0 0)
			(layer "F.Fab")
			(effects
				(font
					(size 1.27 1.27)
				)
			)
		)
		(duplicate_pad_numbers_are_jumpers no)
		(fp_line
			(start -0.7874 -0.4064)
			(end 0.7874 -0.4064)
			(stroke
				(width 0.1524)
				(type default)
			)
			(layer "F.SilkS")
		)
		(fp_line
			(start -0.7874 0.4064)
			(end -0.7874 -0.4064)
			(stroke
				(width 0.1524)
				(type default)
			)
			(layer "F.SilkS")
		)
		(fp_line
			(start 0.7874 -0.4064)
			(end 0.7874 0.4064)
			(stroke
				(width 0.1524)
				(type default)
			)
			(layer "F.SilkS")
		)
		(fp_line
			(start 0.7874 0.4064)
			(end -0.7874 0.4064)
			(stroke
				(width 0.1524)
				(type default)
			)
			(layer "F.SilkS")
		)
		(fp_line
			(start -0.67945 -0.305054)
			(end -0.12065 -0.305054)
			(stroke
				(width 0.1)
				(type default)
			)
			(layer "F.Fab")
		)
		(fp_line
			(start -0.67945 0.3048)
			(end -0.67945 -0.305054)
			(stroke
				(width 0.1)
				(type default)
			)
			(layer "F.Fab")
		)
		(fp_line
			(start -0.12065 -0.305054)
			(end -0.12065 -0.2794)
			(stroke
				(width 0.1)
				(type default)
			)
			(layer "F.Fab")
		)
		(fp_line
			(start -0.12065 -0.2794)
			(end 0.12065 -0.2794)
			(stroke
				(width 0.1)
				(type default)
			)
			(layer "F.Fab")
		)
		(fp_line
			(start -0.12065 0.2794)
			(end -0.12065 0.3048)
			(stroke
				(width 0.1)
				(type default)
			)
			(layer "F.Fab")
		)
		(fp_line
			(start -0.12065 0.3048)
			(end -0.67945 0.3048)
			(stroke
				(width 0.1)
				(type default)
			)
			(layer "F.Fab")
		)
		(fp_line
			(start 0.120396 0.2794)
			(end -0.12065 0.2794)
			(stroke
				(width 0.1)
				(type default)
			)
			(layer "F.Fab")
		)
		(fp_line
			(start 0.120396 0.3048)
			(end 0.120396 0.2794)
			(stroke
				(width 0.1)
				(type default)
			)
			(layer "F.Fab")
		)
		(fp_line
			(start 0.12065 -0.3048)
			(end 0.67945 -0.3048)
			(stroke
				(width 0.1)
				(type default)
			)
			(layer "F.Fab")
		)
		(fp_line
			(start 0.12065 -0.2794)
			(end 0.12065 -0.3048)
			(stroke
				(width 0.1)
				(type default)
			)
			(layer "F.Fab")
		)
		(fp_line
			(start 0.67945 -0.3048)
			(end 0.67945 0.3048)
			(stroke
				(width 0.1)
				(type default)
			)
			(layer "F.Fab")
		)
		(fp_line
			(start 0.67945 0.3048)
			(end 0.120396 0.3048)
			(stroke
				(width 0.1)
				(type default)
			)
			(layer "F.Fab")
		)
		(pad "1" smd circle
			(at -0.40005 0)
			(size 0 0)
			(layers "F.Cu" "F.Mask" "F.Paste")
			(net "P3V3_AUX")
		)
		(pad "2" smd circle
			(at 0.40005 0)
			(size 0 0)
			(layers "F.Cu" "F.Mask" "F.Paste")
			(net "PRSNT_SWB_ISO_N")
		)
	)
)
